(kicad_pcb
	(version 20241229)
	(generator "pcbnew")
	(generator_version "9.0")
	(general
		(thickness 1.62)
		(legacy_teardrops no)
	)
	(paper "A3")
	(title_block
		(title "COM Express 7 Baseboard")
		(date "2025-02-04")
		(rev "1.1.2")
		(company "Antmicro Ltd")
		(comment 1 "www.antmicro.com")
		(comment 9 "footprints 551-555 of 802")
	)
	(layers
		(0 "F.Cu" signal)
		(4 "In1.Cu" signal)
		(6 "In2.Cu" signal)
		(8 "In3.Cu" signal)
		(10 "In4.Cu" signal)
		(12 "In5.Cu" signal)
		(14 "In6.Cu" signal)
		(2 "B.Cu" signal)
		(9 "F.Adhes" user "F.Adhesive")
		(11 "B.Adhes" user "B.Adhesive")
		(13 "F.Paste" user)
		(15 "B.Paste" user)
		(5 "F.SilkS" user "F.Silkscreen")
		(7 "B.SilkS" user "B.Silkscreen")
		(1 "F.Mask" user)
		(3 "B.Mask" user)
		(17 "Dwgs.User" user "User.Drawings")
		(19 "Cmts.User" user "User.Comments")
		(21 "Eco1.User" user "User.Eco1")
		(23 "Eco2.User" user "User.Eco2")
		(25 "Edge.Cuts" user)
		(27 "Margin" user)
		(31 "F.CrtYd" user "F.Courtyard")
		(29 "B.CrtYd" user "B.Courtyard")
		(35 "F.Fab" user)
		(33 "B.Fab" user)
	)
	(footprint "antmicro-footprints:C_0402_1005Metric"
		(layer "B.Cu")
		(at 109.811 160.847571 180)
		(descr "Capacitor SMD 0402")
		(tags "capacitor SMD 0402")
		(property "Reference" "C140"
			(at -3.689 -0.502429 0)
			(layer "B.SilkS")
			(effects
				(font
					(size 0.7 0.7)
					(thickness 0.15)
				)
				(justify left bottom mirror)
			)
		)
		(property "Value" "C_220n_0402"
			(at -1.022927 -2.155213 0)
			(layer "B.Fab")
			(effects
				(font
					(size 0.7 0.7)
					(thickness 0.15)
				)
				(justify left bottom mirror)
			)
		)
		(property "Datasheet" "https://www.yageo.com/en/Chart/Download/pdf/CC0402KRX5R6BB224"
			(at 0 0 180)
			(layer "F.Fab")
			(hide yes)
			(effects
				(font
					(size 1.27 1.27)
					(thickness 0.15)
				)
			)
		)
		(property "Author" "Antmicro"
			(at 219.622 321.695142 0)
			(layer "B.Fab")
			(hide yes)
			(effects
				(font
					(size 1 1)
					(thickness 0.15)
				)
				(justify mirror)
			)
		)
		(property "Dielectric" ""
			(at 219.622 321.695142 0)
			(layer "B.Fab")
			(hide yes)
			(effects
				(font
					(size 1 1)
					(thickness 0.15)
				)
				(justify mirror)
			)
		)
		(property "License" "Apache-2.0"
			(at 219.622 321.695142 0)
			(layer "B.Fab")
			(hide yes)
			(effects
				(font
					(size 1 1)
					(thickness 0.15)
				)
				(justify mirror)
			)
		)
		(property "MPN" "CC0402KRX5R6BB224"
			(at 219.622 321.695142 0)
			(layer "B.Fab")
			(hide yes)
			(effects
				(font
					(size 1 1)
					(thickness 0.15)
				)
				(justify mirror)
			)
		)
		(property "Manufacturer" "YAGEO"
			(at 219.622 321.695142 0)
			(layer "B.Fab")
			(hide yes)
			(effects
				(font
					(size 1 1)
					(thickness 0.15)
				)
				(justify mirror)
			)
		)
		(property "Public" "False"
			(at 219.622 321.695142 0)
			(layer "B.Fab")
			(hide yes)
			(effects
				(font
					(size 1 1)
					(thickness 0.15)
				)
				(justify mirror)
			)
		)
		(property "Val" "220n"
			(at 219.622 321.695142 0)
			(layer "B.Fab")
			(hide yes)
			(effects
				(font
					(size 1 1)
					(thickness 0.15)
				)
				(justify mirror)
			)
		)
		(property "Voltage" ""
			(at 219.622 321.695142 0)
			(layer "B.Fab")
			(hide yes)
			(effects
				(font
					(size 1 1)
					(thickness 0.15)
				)
				(justify mirror)
			)
		)
		(sheetname "PCIe redriver")
		(sheetfile "pcie_redriver.kicad_sch")
		(attr smd)
		(fp_rect
			(start -0.925 0.47)
			(end 0.925 -0.47)
			(stroke
				(width 0.05)
				(type default)
			)
			(fill no)
			(layer "B.CrtYd")
		)
		(fp_line
			(start 0.504 0.25)
			(end -0.494 0.25)
			(stroke
				(width 0.15)
				(type solid)
			)
			(layer "B.Fab")
		)
		(fp_line
			(start 0.504 -0.248)
			(end 0.504 0.25)
			(stroke
				(width 0.15)
				(type solid)
			)
			(layer "B.Fab")
		)
		(fp_line
			(start -0.494 0.25)
			(end -0.494 -0.248)
			(stroke
				(width 0.15)
				(type solid)
			)
			(layer "B.Fab")
		)
		(fp_line
			(start -0.494 -0.248)
			(end 0.504 -0.248)
			(stroke
				(width 0.15)
				(type solid)
			)
			(layer "B.Fab")
		)
		(pad "1" smd roundrect
			(at -0.48 0 180)
			(size 0.59 0.64)
			(layers "B.Cu" "B.Mask" "B.Paste")
			(roundrect_rratio 0.25)
			(net 961 "/PCIe redriver/PCIe_{O}_C.TX2+")
			(pintype "passive")
			(teardrops
				(best_length_ratio 0.2)
				(max_length 1)
				(best_width_ratio 0.9)
				(max_width 2)
				(curved_edges yes)
				(filter_ratio 0.9)
				(enabled yes)
				(allow_two_segments yes)
				(prefer_zone_connections yes)
			)
		)
		(pad "2" smd roundrect
			(at 0.48 0 180)
			(size 0.59 0.64)
			(layers "B.Cu" "B.Mask" "B.Paste")
			(roundrect_rratio 0.25)
			(net 104 "/OCuLink/PCIe_{x4}.TX2+")
			(pintype "passive")
			(teardrops
				(best_length_ratio 0.2)
				(max_length 1)
				(best_width_ratio 0.9)
				(max_width 2)
				(curved_edges yes)
				(filter_ratio 0.9)
				(enabled yes)
				(allow_two_segments yes)
				(prefer_zone_connections yes)
			)
		)
	)
	(footprint "antmicro-footprints:SC70-3"
		(layer "B.Cu")
		(at 100.75 121.96)
		(property "Reference" "D6"
			(at -1.45 0.75 90)
			(layer "B.SilkS")
			(effects
				(font
					(size 0.7 0.7)
					(thickness 0.15)
				)
				(justify right bottom mirror)
			)
		)
		(property "Value" "TPD2E2U06_SC70"
			(at 0 -2.3 0)
			(layer "B.Fab")
			(effects
				(font
					(size 0.7 0.7)
					(thickness 0.15)
				)
				(justify right bottom mirror)
			)
		)
		(property "Datasheet" "https://www.ti.com/lit/ds/symlink/tpd2e2u06.pdf?ts=1706006131823&ref_url=https%253A%252F%252Fwww.ti.com%252Finterface%252Fdiodes%252Fesd-protection-diodes%252Fproducts.html"
			(at 0 0 0)
			(layer "F.Fab")
			(hide yes)
			(effects
				(font
					(size 1.27 1.27)
					(thickness 0.15)
				)
			)
		)
		(property "Author" "Antmicro"
			(at 0 0 0)
			(layer "B.Fab")
			(hide yes)
			(effects
				(font
					(size 1 1)
					(thickness 0.15)
				)
				(justify mirror)
			)
		)
		(property "License" "Apache-2.0"
			(at 0 0 0)
			(layer "B.Fab")
			(hide yes)
			(effects
				(font
					(size 1 1)
					(thickness 0.15)
				)
				(justify mirror)
			)
		)
		(property "MPN" "TPD2E2U06DCKR"
			(at 0 0 0)
			(layer "B.Fab")
			(hide yes)
			(effects
				(font
					(size 1 1)
					(thickness 0.15)
				)
				(justify mirror)
			)
		)
		(property "Manufacturer" "Texas Instruments"
			(at 0 0 0)
			(layer "B.Fab")
			(hide yes)
			(effects
				(font
					(size 1 1)
					(thickness 0.15)
				)
				(justify mirror)
			)
		)
		(sheetname "Com Express 7 MGMT")
		(sheetfile "com_express_7_mgmt.kicad_sch")
		(attr smd)
		(fp_line
			(start 0.627 -1.001)
			(end -0.3 -1)
			(stroke
				(width 0.15)
				(type solid)
			)
			(layer "B.SilkS")
		)
		(fp_line
			(start 0.627 -1.001)
			(end 0.627 -0.6)
			(stroke
				(width 0.15)
				(type solid)
			)
			(layer "B.SilkS")
		)
		(fp_line
			(start 0.627 0.999)
			(end -0.3 1)
			(stroke
				(width 0.15)
				(type solid)
			)
			(layer "B.SilkS")
		)
		(fp_line
			(start 0.627 0.999)
			(end 0.627 0.6)
			(stroke
				(width 0.15)
				(type solid)
			)
			(layer "B.SilkS")
		)
		(fp_line
			(start -1.4 -1)
			(end -0.9 -1)
			(stroke
				(width 0.05)
				(type solid)
			)
			(layer "B.CrtYd")
		)
		(fp_line
			(start -1.4 1)
			(end -1.4 -1)
			(stroke
				(width 0.05)
				(type solid)
			)
			(layer "B.CrtYd")
		)
		(fp_line
			(start -1.4 1)
			(end -0.9 1)
			(stroke
				(width 0.05)
				(type solid)
			)
			(layer "B.CrtYd")
		)
		(fp_line
			(start -0.9 -1.3)
			(end 0.9 -1.3)
			(stroke
				(width 0.05)
				(type solid)
			)
			(layer "B.CrtYd")
		)
		(fp_line
			(start -0.9 -1)
			(end -0.9 -1.3)
			(stroke
				(width 0.05)
				(type solid)
			)
			(layer "B.CrtYd")
		)
		(fp_line
			(start -0.9 1)
			(end -0.9 1.3)
			(stroke
				(width 0.05)
				(type solid)
			)
			(layer "B.CrtYd")
		)
		(fp_line
			(start 0.9 -1.3)
			(end 0.9 -0.4)
			(stroke
				(width 0.05)
				(type solid)
			)
			(layer "B.CrtYd")
		)
		(fp_line
			(start 0.9 -0.4)
			(end 1.4 -0.4)
			(stroke
				(width 0.05)
				(type solid)
			)
			(layer "B.CrtYd")
		)
		(fp_line
			(start 0.9 0.4)
			(end 0.9 1.3)
			(stroke
				(width 0.05)
				(type solid)
			)
			(layer "B.CrtYd")
		)
		(fp_line
			(start 0.9 1.3)
			(end -0.9 1.3)
			(stroke
				(width 0.05)
				(type solid)
			)
			(layer "B.CrtYd")
		)
		(fp_line
			(start 1.4 -0.4)
			(end 1.4 0.4)
			(stroke
				(width 0.05)
				(type solid)
			)
			(layer "B.CrtYd")
		)
		(fp_line
			(start 1.4 0.4)
			(end 0.9 0.4)
			(stroke
				(width 0.05)
				(type solid)
			)
			(layer "B.CrtYd")
		)
		(fp_rect
			(start -0.623 0.999)
			(end 0.627 -1.001)
			(stroke
				(width 0.15)
				(type solid)
			)
			(fill no)
			(layer "B.Fab")
		)
		(pad "1" smd rect
			(at -1.051 0.65 270)
			(size 0.6 0.6)
			(layers "B.Cu" "B.Mask" "B.Paste")
			(net 928 "unconnected-(D6-Pad1)")
			(pinfunction "1")
			(pintype "passive+no_connect")
			(teardrops
				(best_length_ratio 0.2)
				(max_length 1)
				(best_width_ratio 0.9)
				(max_width 2)
				(curved_edges yes)
				(filter_ratio 0.9)
				(enabled yes)
				(allow_two_segments yes)
				(prefer_zone_connections yes)
			)
		)
		(pad "2" smd rect
			(at -1.051 -0.65 270)
			(size 0.6 0.6)
			(layers "B.Cu" "B.Mask" "B.Paste")
			(net 84 "/Com Express 7 MGMT/PWRBTN")
			(pinfunction "2")
			(pintype "passive")
			(teardrops
				(best_length_ratio 0.2)
				(max_length 1)
				(best_width_ratio 0.9)
				(max_width 2)
				(curved_edges yes)
				(filter_ratio 0.9)
				(enabled yes)
				(allow_two_segments yes)
				(prefer_zone_connections yes)
			)
		)
		(pad "3" smd rect
			(at 1.05 0 270)
			(size 0.6 0.6)
			(layers "B.Cu" "B.Mask" "B.Paste")
			(net 1 "GND")
			(pinfunction "3")
			(pintype "passive")
			(teardrops
				(best_length_ratio 0.2)
				(max_length 1)
				(best_width_ratio 0.9)
				(max_width 2)
				(curved_edges yes)
				(filter_ratio 0.9)
				(enabled yes)
				(allow_two_segments yes)
				(prefer_zone_connections yes)
			)
		)
	)
	(footprint "antmicro-footprints:TP_SMD_0.75mm"
		(layer "B.Cu")
		(at 189.1 164.25 -90)
		(property "Reference" "TP40"
			(at -0.35 3.3 0)
			(layer "B.SilkS")
			(effects
				(font
					(size 0.7 0.7)
					(thickness 0.15)
				)
				(justify right top mirror)
			)
		)
		(property "Value" "TP_0.75mm_SMD"
			(at 3.225 -53.865 90)
			(layer "B.Fab")
			(hide yes)
			(effects
				(font
					(size 0.7 0.7)
					(thickness 0.15)
				)
				(justify left bottom mirror)
			)
		)
		(property "Author" "Antmicro"
			(at 435.1 311.62 90)
			(layer "B.Fab")
			(hide yes)
			(effects
				(font
					(size 1 1)
					(thickness 0.15)
				)
				(justify mirror)
			)
		)
		(property "License" "Apache-2.0"
			(at 435.1 311.62 90)
			(layer "B.Fab")
			(hide yes)
			(effects
				(font
					(size 1 1)
					(thickness 0.15)
				)
				(justify mirror)
			)
		)
		(property "MPN" ""
			(at 435.1 311.62 90)
			(layer "B.Fab")
			(hide yes)
			(effects
				(font
					(size 1 1)
					(thickness 0.15)
				)
				(justify mirror)
			)
		)
		(property "Manufacturer" ""
			(at 435.1 311.62 90)
			(layer "B.Fab")
			(hide yes)
			(effects
				(font
					(size 1 1)
					(thickness 0.15)
				)
				(justify mirror)
			)
		)
		(property "Public" "False"
			(at 435.1 311.62 90)
			(layer "B.Fab")
			(hide yes)
			(effects
				(font
					(size 1 1)
					(thickness 0.15)
				)
				(justify mirror)
			)
		)
		(sheetname "Com Express 7 MGMT")
		(sheetfile "com_express_7_mgmt.kicad_sch")
		(attr exclude_from_pos_files exclude_from_bom)
		(fp_circle
			(center 0 0)
			(end 0.475 0)
			(stroke
				(width 0.05)
				(type default)
			)
			(fill no)
			(layer "B.CrtYd")
		)
		(pad "1" smd circle
			(at 0 0 270)
			(size 0.75 0.75)
			(layers "B.Cu" "B.Mask")
			(net 366 "Net-(J12D-WDT)")
			(pinfunction "1")
			(pintype "passive")
			(teardrops
				(best_length_ratio 0.4)
				(max_length 1)
				(best_width_ratio 0.9)
				(max_width 2)
				(curved_edges yes)
				(filter_ratio 0.9)
				(enabled yes)
				(allow_two_segments yes)
				(prefer_zone_connections yes)
			)
		)
	)
	(footprint "antmicro-footprints:C_0402_1005Metric"
		(layer "B.Cu")
		(at 196.425233 139.130616 135)
		(descr "Capacitor SMD 0402")
		(tags "capacitor SMD 0402")
		(property "Reference" "C124"
			(at -2.768935 -0.026347 135)
			(layer "B.SilkS")
			(effects
				(font
					(size 0.7 0.7)
					(thickness 0.15)
				)
				(justify right bottom mirror)
			)
		)
		(property "Value" "C_220n_0402"
			(at -1.022927 -2.155213 135)
			(layer "B.Fab")
			(effects
				(font
					(size 0.7 0.7)
					(thickness 0.15)
				)
				(justify right bottom mirror)
			)
		)
		(property "Datasheet" "https://www.yageo.com/en/Chart/Download/pdf/CC0402KRX5R6BB224"
			(at 0 0 135)
			(layer "F.Fab")
			(hide yes)
			(effects
				(font
					(size 1.27 1.27)
					(thickness 0.15)
				)
			)
		)
		(property "Author" "Antmicro"
			(at 339.710001 -39.09 45)
			(layer "B.Fab")
			(hide yes)
			(effects
				(font
					(size 1 1)
					(thickness 0.15)
				)
				(justify mirror)
			)
		)
		(property "Dielectric" ""
			(at 339.710001 -39.09 45)
			(layer "B.Fab")
			(hide yes)
			(effects
				(font
					(size 1 1)
					(thickness 0.15)
				)
				(justify mirror)
			)
		)
		(property "License" "Apache-2.0"
			(at 339.710001 -39.09 45)
			(layer "B.Fab")
			(hide yes)
			(effects
				(font
					(size 1 1)
					(thickness 0.15)
				)
				(justify mirror)
			)
		)
		(property "MPN" "CC0402KRX5R6BB224"
			(at 339.710001 -39.09 45)
			(layer "B.Fab")
			(hide yes)
			(effects
				(font
					(size 1 1)
					(thickness 0.15)
				)
				(justify mirror)
			)
		)
		(property "Manufacturer" "YAGEO"
			(at 339.710001 -39.09 45)
			(layer "B.Fab")
			(hide yes)
			(effects
				(font
					(size 1 1)
					(thickness 0.15)
				)
				(justify mirror)
			)
		)
		(property "Public" "False"
			(at 339.710001 -39.09 45)
			(layer "B.Fab")
			(hide yes)
			(effects
				(font
					(size 1 1)
					(thickness 0.15)
				)
				(justify mirror)
			)
		)
		(property "Val" "220n"
			(at 339.710001 -39.09 45)
			(layer "B.Fab")
			(hide yes)
			(effects
				(font
					(size 1 1)
					(thickness 0.15)
				)
				(justify mirror)
			)
		)
		(property "Voltage" ""
			(at 339.710001 -39.09 45)
			(layer "B.Fab")
			(hide yes)
			(effects
				(font
					(size 1 1)
					(thickness 0.15)
				)
				(justify mirror)
			)
		)
		(sheetname "PCIe redriver")
		(sheetfile "pcie_redriver.kicad_sch")
		(attr smd)
		(fp_poly
			(pts
				(xy -0.925 0.47) (xy 0.925 0.47) (xy 0.925 -0.47) (xy -0.925 -0.47)
			)
			(stroke
				(width 0.05)
				(type default)
			)
			(fill no)
			(layer "B.CrtYd")
		)
		(fp_line
			(start 0.504 -0.248)
			(end 0.504 0.25)
			(stroke
				(width 0.15)
				(type solid)
			)
			(layer "B.Fab")
		)
		(fp_line
			(start 0.504 0.25)
			(end -0.494 0.25)
			(stroke
				(width 0.15)
				(type solid)
			)
			(layer "B.Fab")
		)
		(fp_line
			(start -0.494 -0.248)
			(end 0.504 -0.248)
			(stroke
				(width 0.15)
				(type solid)
			)
			(layer "B.Fab")
		)
		(fp_line
			(start -0.494 0.25)
			(end -0.494 -0.248)
			(stroke
				(width 0.15)
				(type solid)
			)
			(layer "B.Fab")
		)
		(pad "1" smd roundrect
			(at -0.48 0 135)
			(size 0.59 0.64)
			(layers "B.Cu" "B.Mask" "B.Paste")
			(roundrect_rratio 0.25)
			(net 213 "/Com Express 7 Interfaces/PCIe_{B1x4}.RX2-")
			(pintype "passive")
			(teardrops
				(best_length_ratio 0.2)
				(max_length 1)
				(best_width_ratio 0.9)
				(max_width 2)
				(curved_edges yes)
				(filter_ratio 0.9)
				(enabled yes)
				(allow_two_segments yes)
				(prefer_zone_connections yes)
			)
		)
		(pad "2" smd roundrect
			(at 0.48 0 135)
			(size 0.59 0.64)
			(layers "B.Cu" "B.Mask" "B.Paste")
			(roundrect_rratio 0.25)
			(net 105 "/PCIe redriver/PCIe_{I}_C.RX2-")
			(pintype "passive")
			(teardrops
				(best_length_ratio 0.2)
				(max_length 1)
				(best_width_ratio 0.9)
				(max_width 2)
				(curved_edges yes)
				(filter_ratio 0.9)
				(enabled yes)
				(allow_two_segments yes)
				(prefer_zone_connections yes)
			)
		)
	)
	(footprint "antmicro-footprints:R_0402_1005Metric"
		(layer "B.Cu")
		(at 100.1 85.46 180)
		(descr "Resistor SMD 0402")
		(tags "resistor SMD 0402")
		(property "Reference" "R67"
			(at -1.05 -1.35 0)
			(layer "B.SilkS")
			(effects
				(font
					(size 0.7 0.7)
					(thickness 0.15)
				)
				(justify left bottom mirror)
			)
		)
		(property "Value" "R_5k1_0402"
			(at -1.011843 -1.772047 0)
			(layer "B.Fab")
			(effects
				(font
					(size 0.7 0.7)
					(thickness 0.15)
				)
				(justify left bottom mirror)
			)
		)
		(property "Datasheet" "https://www.bourns.com/docs/product-datasheets/cr.pdf"
			(at 0 0 180)
			(layer "F.Fab")
			(hide yes)
			(effects
				(font
					(size 1.27 1.27)
					(thickness 0.15)
				)
			)
		)
		(property "Author" "Antmicro"
			(at 200 170.92 0)
			(layer "B.Fab")
			(hide yes)
			(effects
				(font
					(size 1 1)
					(thickness 0.15)
				)
				(justify mirror)
			)
		)
		(property "License" "Apache-2.0"
			(at 200 170.92 0)
			(layer "B.Fab")
			(hide yes)
			(effects
				(font
					(size 1 1)
					(thickness 0.15)
				)
				(justify mirror)
			)
		)
		(property "MPN" "CR0402-FX-5101GLF"
			(at 200 170.92 0)
			(layer "B.Fab")
			(hide yes)
			(effects
				(font
					(size 1 1)
					(thickness 0.15)
				)
				(justify mirror)
			)
		)
		(property "Manufacturer" "Bourns"
			(at 200 170.92 0)
			(layer "B.Fab")
			(hide yes)
			(effects
				(font
					(size 1 1)
					(thickness 0.15)
				)
				(justify mirror)
			)
		)
		(property "Public" "False"
			(at 200 170.92 0)
			(layer "B.Fab")
			(hide yes)
			(effects
				(font
					(size 1 1)
					(thickness 0.15)
				)
				(justify mirror)
			)
		)
		(property "Tolerance" "1%"
			(at 200 170.92 0)
			(layer "B.Fab")
			(hide yes)
			(effects
				(font
					(size 1 1)
					(thickness 0.15)
				)
				(justify mirror)
			)
		)
		(property "Val" "5k1"
			(at 200 170.92 0)
			(layer "B.Fab")
			(hide yes)
			(effects
				(font
					(size 1 1)
					(thickness 0.15)
				)
				(justify mirror)
			)
		)
		(sheetname "USB-C console")
		(sheetfile "usb-c_console.kicad_sch")
		(attr smd)
		(fp_rect
			(start -0.925 0.47)
			(end 0.925 -0.47)
			(stroke
				(width 0.05)
				(type default)
			)
			(fill no)
			(layer "B.CrtYd")
		)
		(fp_rect
			(start -0.5 0.25)
			(end 0.5 -0.25)
			(stroke
				(width 0.15)
				(type solid)
			)
			(fill no)
			(layer "B.Fab")
		)
		(pad "1" smd roundrect
			(at -0.48 0 180)
			(size 0.59 0.64)
			(layers "B.Cu" "B.Mask" "B.Paste")
			(roundrect_rratio 0.25)
			(net 176 "Net-(J3-CC_{1})")
			(pintype "passive")
			(teardrops
				(best_length_ratio 0.2)
				(max_length 1)
				(best_width_ratio 0.9)
				(max_width 2)
				(curved_edges yes)
				(filter_ratio 0.9)
				(enabled yes)
				(allow_two_segments yes)
				(prefer_zone_connections yes)
			)
		)
		(pad "2" smd roundrect
			(at 0.48 0 180)
			(size 0.59 0.64)
			(layers "B.Cu" "B.Mask" "B.Paste")
			(roundrect_rratio 0.25)
			(net 1 "GND")
			(pintype "passive")
			(teardrops
				(best_length_ratio 0.2)
				(max_length 1)
				(best_width_ratio 0.9)
				(max_width 2)
				(curved_edges yes)
				(filter_ratio 0.9)
				(enabled yes)
				(allow_two_segments yes)
				(prefer_zone_connections yes)
			)
		)
	)
)
